(kicad_pcb
	(version 20260206)
	(generator "pcbnew")
	(generator_version "10.0")
	(general
		(thickness 1.6)
		(legacy_teardrops no)
	)
	(paper "A4")
	(title_block
		(title "12092022_DA0F0TMDCD0_F0T_Management_Board_D_brd_V3_OCP.brd")
		(comment 1 "Grand Teton / footprints 633-637 of 1440")
	)
	(layers
		(0 "F.Cu" signal "TOP")
		(4 "In1.Cu" signal "GND")
		(6 "In2.Cu" signal "IN1")
		(8 "In3.Cu" signal "GND1")
		(10 "In4.Cu" signal "IN2")
		(12 "In5.Cu" signal "VCC")
		(14 "In6.Cu" signal "VCC1")
		(16 "In7.Cu" signal "IN3")
		(18 "In8.Cu" signal "GND2")
		(20 "In9.Cu" signal "IN4")
		(22 "In10.Cu" signal "GND3")
		(2 "B.Cu" signal "BOTTOM")
		(9 "F.Adhes" user "F.Adhesive")
		(11 "B.Adhes" user "B.Adhesive")
		(13 "F.Paste" user "Package Geometry/Pastemask Top")
		(15 "B.Paste" user "Package Geometry/Pastemask Bottom")
		(5 "F.SilkS" user "Ref Des/Silkscreen Top")
		(7 "B.SilkS" user "Ref Des/Silkscreen Bottom")
		(1 "F.Mask" user "Board Geometry/Soldermask Top")
		(3 "B.Mask" user "Board Geometry/Soldermask Bottom")
		(17 "Dwgs.User" user "User.Drawings")
		(19 "Cmts.User" user "User.Comments")
		(21 "Eco1.User" user "User.Eco1")
		(23 "Eco2.User" user "User.Eco2")
		(25 "Edge.Cuts" user "Board Geometry/Outline")
		(27 "Margin" user)
		(31 "F.CrtYd" user "Package Geometry/Place Bound Top")
		(29 "B.CrtYd" user "Package Geometry/Place Bound Bottom")
		(35 "F.Fab" user "Ref Des/Assembly Top")
		(33 "B.Fab" user "Ref Des/Assembly Bottom")
	)
	(footprint ""
		(layer "F.Cu")
		(at 79.202026 -94.856046 180)
		(property "Reference" "J10"
			(at 4.589526 -5.741416 0)
			(unlocked yes)
			(layer "F.SilkS")
			(effects
				(font
					(size 0.7874 0.5842)
					(thickness 0.1524)
				)
				(justify left)
			)
		)
		(property "Value" ""
			(at 0 0 180)
			(layer "F.Fab")
			(effects
				(font
					(size 1.27 1.27)
				)
			)
		)
		(duplicate_pad_numbers_are_jumpers no)
		(fp_line
			(start 2.500122 5.150104)
			(end -2.500122 5.150104)
			(stroke
				(width 0.1524)
				(type default)
			)
			(layer "F.SilkS")
		)
		(fp_line
			(start 2.500122 5.08)
			(end 2.500122 5.150104)
			(stroke
				(width 0.1524)
				(type default)
			)
			(layer "F.SilkS")
		)
		(fp_line
			(start 2.500122 2.4384)
			(end 2.500122 3.3782)
			(stroke
				(width 0.1524)
				(type default)
			)
			(layer "F.SilkS")
		)
		(fp_line
			(start 2.500122 -3.3782)
			(end 2.500122 -2.4384)
			(stroke
				(width 0.1524)
				(type default)
			)
			(layer "F.SilkS")
		)
		(fp_line
			(start 2.500122 -5.150104)
			(end 2.500122 -5.08)
			(stroke
				(width 0.1524)
				(type default)
			)
			(layer "F.SilkS")
		)
		(fp_line
			(start -2.500122 5.150104)
			(end -2.500122 5.08)
			(stroke
				(width 0.1524)
				(type default)
			)
			(layer "F.SilkS")
		)
		(fp_line
			(start -2.500122 3.3782)
			(end -2.500122 2.9464)
			(stroke
				(width 0.1524)
				(type default)
			)
			(layer "F.SilkS")
		)
		(fp_line
			(start -2.500122 -2.9464)
			(end -2.500122 -3.3782)
			(stroke
				(width 0.1524)
				(type default)
			)
			(layer "F.SilkS")
		)
		(fp_line
			(start -2.500122 -5.08)
			(end -2.500122 -5.150104)
			(stroke
				(width 0.1524)
				(type default)
			)
			(layer "F.SilkS")
		)
		(fp_line
			(start -2.500122 -5.150104)
			(end 2.500122 -5.150104)
			(stroke
				(width 0.1524)
				(type default)
			)
			(layer "F.SilkS")
		)
		(fp_poly
			(pts
				(xy -4.0386 -2.068322) (xy -4.0386 -3.084322) (xy -3.0226 -2.576322)
			)
			(stroke
				(width 0)
				(type default)
			)
			(fill yes)
			(layer "F.SilkS")
		)
		(fp_line
			(start 2.500122 5.150104)
			(end 2.500122 -5.150104)
			(stroke
				(width 0.1)
				(type default)
			)
			(layer "F.Fab")
		)
		(fp_line
			(start 2.500122 -5.150104)
			(end -2.500122 -5.150104)
			(stroke
				(width 0.1)
				(type default)
			)
			(layer "F.Fab")
		)
		(fp_line
			(start -2.500122 5.150104)
			(end 2.500122 5.150104)
			(stroke
				(width 0.1)
				(type default)
			)
			(layer "F.Fab")
		)
		(fp_line
			(start -2.500122 -5.150104)
			(end -2.500122 5.150104)
			(stroke
				(width 0.1)
				(type default)
			)
			(layer "F.Fab")
		)
		(fp_poly
			(pts
				(xy -4.0894 -1.992122) (xy -4.0894 -3.008122) (xy -3.0734 -2.500122)
			)
			(stroke
				(width 0)
				(type default)
			)
			(fill yes)
			(layer "F.Fab")
		)
		(fp_text user "11"
			(at 3.814826 2.259584 0)
			(unlocked yes)
			(layer "F.SilkS")
			(effects
				(font
					(size 0.7874 0.5842)
					(thickness 0.1524)
				)
			)
		)
		(fp_text user "7"
			(at 3.535426 -2.566416 0)
			(unlocked yes)
			(layer "F.SilkS")
			(effects
				(font
					(size 0.7874 0.5842)
					(thickness 0.1524)
				)
			)
		)
		(fp_text user "6"
			(at -3.779774 3.341624 180)
			(unlocked yes)
			(layer "F.SilkS")
			(effects
				(font
					(size 0.7874 0.5842)
					(thickness 0.1524)
				)
			)
		)
		(fp_text user "7"
			(at 3.520948 -2.048002 90)
			(unlocked yes)
			(layer "F.Fab")
			(effects
				(font
					(size 0.7874 0.5842)
					(thickness 0.1524)
				)
			)
		)
		(fp_text user "11"
			(at 3.495548 2.028444 90)
			(unlocked yes)
			(layer "F.Fab")
			(effects
				(font
					(size 0.7874 0.5842)
					(thickness 0.1524)
				)
			)
		)
		(fp_text user "6"
			(at -3.591052 2.574798 90)
			(unlocked yes)
			(layer "F.Fab")
			(effects
				(font
					(size 0.7874 0.5842)
					(thickness 0.1524)
				)
			)
		)
		(pad "1" smd rect
			(at -2.109978 -2.500122 270)
			(size 0.6096 1.651)
			(layers "F.Cu" "F.Mask" "F.Paste")
			(net "SPI_BMC_TPM_CLK_R")
		)
		(pad "2" smd rect
			(at -2.109978 -1.500124 270)
			(size 0.6096 1.651)
			(layers "F.Cu" "F.Mask" "F.Paste")
			(net "RST_BMC_EXTRST_R3_N")
		)
		(pad "3" smd rect
			(at -2.109978 -0.499872 270)
			(size 0.6096 1.651)
			(layers "F.Cu" "F.Mask" "F.Paste")
			(net "SPI_BMC_TPM_MOSI_R")
		)
		(pad "4" smd rect
			(at -2.109978 0.499872 270)
			(size 0.6096 1.651)
			(layers "F.Cu" "F.Mask" "F.Paste")
			(net "SPI_BMC_TPM_MISO_R")
		)
		(pad "5" smd rect
			(at -2.109978 1.500124 270)
			(size 0.6096 1.651)
			(layers "F.Cu" "F.Mask" "F.Paste")
			(net "SPI_BMC_TPM_CS2_N_R")
		)
		(pad "6" smd rect
			(at -2.109978 2.500122 270)
			(size 0.6096 1.651)
			(layers "F.Cu" "F.Mask" "F.Paste")
			(net "SMB_BMC_TPM_MM16_SDA")
		)
		(pad "7" smd rect
			(at 2.109978 -1.999996 90)
			(size 0.6096 1.651)
			(layers "F.Cu" "F.Mask" "F.Paste")
			(net "P3V3_AUX")
		)
		(pad "8" smd rect
			(at 2.109978 -0.999998 90)
			(size 0.6096 1.651)
			(layers "F.Cu" "F.Mask" "F.Paste")
			(net "FM_TPM_PRSNT_1_N")
		)
		(pad "9" smd rect
			(at 2.109978 0 90)
			(size 0.6096 1.651)
			(layers "F.Cu" "F.Mask" "F.Paste")
			(net "IRQ_BMC_TPM_SPI_R_N")
		)
		(pad "10" smd rect
			(at 2.109978 0.999998 90)
			(size 0.6096 1.651)
			(layers "F.Cu" "F.Mask" "F.Paste")
			(net "SMB_BMC_TPM_MM16_SCL")
		)
		(pad "11" smd rect
			(at 2.109978 1.999996 90)
			(size 0.6096 1.651)
			(layers "F.Cu" "F.Mask" "F.Paste")
			(net "GND")
		)
		(pad "G1" smd rect
			(at 0 -4.219956 270)
			(size 1.4224 5.8674)
			(layers "F.Cu" "F.Mask" "F.Paste")
			(net "GND")
		)
		(pad "G2" smd rect
			(at 0 4.219956 90)
			(size 1.4224 5.8674)
			(layers "F.Cu" "F.Mask" "F.Paste")
			(net "GND")
		)
	)
	(footprint ""
		(layer "F.Cu")
		(at 37.592 -53.086 180)
		(property "Reference" "C142"
			(at 0 0 180)
			(layer "F.SilkS")
			(hide yes)
			(effects
				(font
					(size 1.27 1.27)
				)
			)
		)
		(property "Value" ""
			(at 0 0 180)
			(layer "F.Fab")
			(effects
				(font
					(size 1.27 1.27)
				)
			)
		)
		(duplicate_pad_numbers_are_jumpers no)
		(fp_line
			(start 1.651 0.8382)
			(end -1.651 0.8382)
			(stroke
				(width 0.1524)
				(type default)
			)
			(layer "F.SilkS")
		)
		(fp_line
			(start 1.651 -0.8382)
			(end 1.651 0.8382)
			(stroke
				(width 0.1524)
				(type default)
			)
			(layer "F.SilkS")
		)
		(fp_line
			(start 0 0.8382)
			(end 0 -0.8382)
			(stroke
				(width 0.1524)
				(type default)
			)
			(layer "F.SilkS")
		)
		(fp_line
			(start -1.651 0.8382)
			(end -1.651 -0.8382)
			(stroke
				(width 0.1524)
				(type default)
			)
			(layer "F.SilkS")
		)
		(fp_line
			(start -1.651 -0.8382)
			(end 1.651 -0.8382)
			(stroke
				(width 0.1524)
				(type default)
			)
			(layer "F.SilkS")
		)
		(fp_line
			(start 1.55956 0.7366)
			(end 1.55956 -0.7366)
			(stroke
				(width 0.1)
				(type default)
			)
			(layer "F.Fab")
		)
		(fp_line
			(start 1.55956 -0.7366)
			(end 1.524 -0.7366)
			(stroke
				(width 0.1)
				(type default)
			)
			(layer "F.Fab")
		)
		(fp_line
			(start 1.524 0.7366)
			(end 1.55956 0.7366)
			(stroke
				(width 0.1)
				(type default)
			)
			(layer "F.Fab")
		)
		(fp_line
			(start 1.524 -0.7366)
			(end -1.524 -0.7366)
			(stroke
				(width 0.1)
				(type default)
			)
			(layer "F.Fab")
		)
		(fp_line
			(start -1.524 0.7366)
			(end 1.524 0.7366)
			(stroke
				(width 0.1)
				(type default)
			)
			(layer "F.Fab")
		)
		(fp_line
			(start -1.524 -0.7366)
			(end -1.55956 -0.7366)
			(stroke
				(width 0.1)
				(type default)
			)
			(layer "F.Fab")
		)
		(fp_line
			(start -1.55956 0.7366)
			(end -1.524 0.7366)
			(stroke
				(width 0.1)
				(type default)
			)
			(layer "F.Fab")
		)
		(fp_line
			(start -1.55956 -0.7366)
			(end -1.55956 0.7366)
			(stroke
				(width 0.1)
				(type default)
			)
			(layer "F.Fab")
		)
		(pad "1" smd rect
			(at -0.94996 0)
			(size 1.1176 1.3716)
			(layers "F.Cu" "F.Mask" "F.Paste")
			(net "P1V8_AUX")
		)
		(pad "2" smd rect
			(at 0.94996 0)
			(size 1.1176 1.3716)
			(layers "F.Cu" "F.Mask" "F.Paste")
			(net "GND")
		)
	)
	(footprint ""
		(layer "F.Cu")
		(at 9.271 -31.837122 -90)
		(property "Reference" "PC214"
			(at 0 0 270)
			(layer "F.SilkS")
			(hide yes)
			(effects
				(font
					(size 1.27 1.27)
				)
			)
		)
		(property "Value" ""
			(at 0 0 270)
			(layer "F.Fab")
			(effects
				(font
					(size 1.27 1.27)
				)
			)
		)
		(duplicate_pad_numbers_are_jumpers no)
		(fp_line
			(start -1.651 0.8382)
			(end -1.651 -0.8382)
			(stroke
				(width 0.1524)
				(type default)
			)
			(layer "F.SilkS")
		)
		(fp_line
			(start 0 0.8382)
			(end 0 -0.8382)
			(stroke
				(width 0.1524)
				(type default)
			)
			(layer "F.SilkS")
		)
		(fp_line
			(start 1.651 0.8382)
			(end -1.651 0.8382)
			(stroke
				(width 0.1524)
				(type default)
			)
			(layer "F.SilkS")
		)
		(fp_line
			(start -1.651 -0.8382)
			(end 1.651 -0.8382)
			(stroke
				(width 0.1524)
				(type default)
			)
			(layer "F.SilkS")
		)
		(fp_line
			(start 1.651 -0.8382)
			(end 1.651 0.8382)
			(stroke
				(width 0.1524)
				(type default)
			)
			(layer "F.SilkS")
		)
		(fp_line
			(start -1.55956 0.7366)
			(end -1.524 0.7366)
			(stroke
				(width 0.1)
				(type default)
			)
			(layer "F.Fab")
		)
		(fp_line
			(start -1.524 0.7366)
			(end 1.524 0.7366)
			(stroke
				(width 0.1)
				(type default)
			)
			(layer "F.Fab")
		)
		(fp_line
			(start 1.524 0.7366)
			(end 1.55956 0.7366)
			(stroke
				(width 0.1)
				(type default)
			)
			(layer "F.Fab")
		)
		(fp_line
			(start 1.55956 0.7366)
			(end 1.55956 -0.7366)
			(stroke
				(width 0.1)
				(type default)
			)
			(layer "F.Fab")
		)
		(fp_line
			(start -1.55956 -0.7366)
			(end -1.55956 0.7366)
			(stroke
				(width 0.1)
				(type default)
			)
			(layer "F.Fab")
		)
		(fp_line
			(start -1.524 -0.7366)
			(end -1.55956 -0.7366)
			(stroke
				(width 0.1)
				(type default)
			)
			(layer "F.Fab")
		)
		(fp_line
			(start 1.524 -0.7366)
			(end -1.524 -0.7366)
			(stroke
				(width 0.1)
				(type default)
			)
			(layer "F.Fab")
		)
		(fp_line
			(start 1.55956 -0.7366)
			(end 1.524 -0.7366)
			(stroke
				(width 0.1)
				(type default)
			)
			(layer "F.Fab")
		)
		(pad "1" smd rect
			(at -0.94996 0 90)
			(size 1.1176 1.3716)
			(layers "F.Cu" "F.Mask" "F.Paste")
			(net "P5V_AUX")
		)
		(pad "2" smd rect
			(at 0.94996 0 90)
			(size 1.1176 1.3716)
			(layers "F.Cu" "F.Mask" "F.Paste")
			(net "GND")
		)
	)
	(footprint ""
		(layer "F.Cu")
		(at 63.246 -81.788)
		(property "Reference" "R507"
			(at 0 0 0)
			(layer "F.SilkS")
			(hide yes)
			(effects
				(font
					(size 1.27 1.27)
				)
			)
		)
		(property "Value" ""
			(at 0 0 0)
			(layer "F.Fab")
			(effects
				(font
					(size 1.27 1.27)
				)
			)
		)
		(duplicate_pad_numbers_are_jumpers no)
		(fp_line
			(start -0.7874 -0.4064)
			(end 0.7874 -0.4064)
			(stroke
				(width 0.1524)
				(type default)
			)
			(layer "F.SilkS")
		)
		(fp_line
			(start -0.7874 0.4064)
			(end -0.7874 -0.4064)
			(stroke
				(width 0.1524)
				(type default)
			)
			(layer "F.SilkS")
		)
		(fp_line
			(start 0.7874 -0.4064)
			(end 0.7874 0.4064)
			(stroke
				(width 0.1524)
				(type default)
			)
			(layer "F.SilkS")
		)
		(fp_line
			(start 0.7874 0.4064)
			(end -0.7874 0.4064)
			(stroke
				(width 0.1524)
				(type default)
			)
			(layer "F.SilkS")
		)
		(fp_line
			(start -0.67945 -0.305054)
			(end -0.12065 -0.305054)
			(stroke
				(width 0.1)
				(type default)
			)
			(layer "F.Fab")
		)
		(fp_line
			(start -0.67945 0.3048)
			(end -0.67945 -0.305054)
			(stroke
				(width 0.1)
				(type default)
			)
			(layer "F.Fab")
		)
		(fp_line
			(start -0.12065 -0.305054)
			(end -0.12065 -0.2794)
			(stroke
				(width 0.1)
				(type default)
			)
			(layer "F.Fab")
		)
		(fp_line
			(start -0.12065 -0.2794)
			(end 0.12065 -0.2794)
			(stroke
				(width 0.1)
				(type default)
			)
			(layer "F.Fab")
		)
		(fp_line
			(start -0.12065 0.2794)
			(end -0.12065 0.3048)
			(stroke
				(width 0.1)
				(type default)
			)
			(layer "F.Fab")
		)
		(fp_line
			(start -0.12065 0.3048)
			(end -0.67945 0.3048)
			(stroke
				(width 0.1)
				(type default)
			)
			(layer "F.Fab")
		)
		(fp_line
			(start 0.120396 0.2794)
			(end -0.12065 0.2794)
			(stroke
				(width 0.1)
				(type default)
			)
			(layer "F.Fab")
		)
		(fp_line
			(start 0.120396 0.3048)
			(end 0.120396 0.2794)
			(stroke
				(width 0.1)
				(type default)
			)
			(layer "F.Fab")
		)
		(fp_line
			(start 0.12065 -0.3048)
			(end 0.67945 -0.3048)
			(stroke
				(width 0.1)
				(type default)
			)
			(layer "F.Fab")
		)
		(fp_line
			(start 0.12065 -0.2794)
			(end 0.12065 -0.3048)
			(stroke
				(width 0.1)
				(type default)
			)
			(layer "F.Fab")
		)
		(fp_line
			(start 0.67945 -0.3048)
			(end 0.67945 0.3048)
			(stroke
				(width 0.1)
				(type default)
			)
			(layer "F.Fab")
		)
		(fp_line
			(start 0.67945 0.3048)
			(end 0.120396 0.3048)
			(stroke
				(width 0.1)
				(type default)
			)
			(layer "F.Fab")
		)
		(pad "1" smd circle
			(at -0.40005 0)
			(size 0 0)
			(layers "F.Cu" "F.Mask" "F.Paste")
			(net "MB_JTAG_PLD_R_JTAGEN")
		)
		(pad "2" smd circle
			(at 0.40005 0)
			(size 0 0)
			(layers "F.Cu" "F.Mask" "F.Paste")
			(net "GND")
		)
	)
	(footprint ""
		(layer "F.Cu")
		(at 74.09815 -92.204032 180)
		(property "Reference" "C144"
			(at 0 0 180)
			(layer "F.SilkS")
			(hide yes)
			(effects
				(font
					(size 1.27 1.27)
				)
			)
		)
		(property "Value" ""
			(at 0 0 180)
			(layer "F.Fab")
			(effects
				(font
					(size 1.27 1.27)
				)
			)
		)
		(duplicate_pad_numbers_are_jumpers no)
		(fp_line
			(start 0.7874 0.4064)
			(end -0.7874 0.4064)
			(stroke
				(width 0.1524)
				(type default)
			)
			(layer "F.SilkS")
		)
		(fp_line
			(start 0.7874 -0.4064)
			(end 0.7874 0.4064)
			(stroke
				(width 0.1524)
				(type default)
			)
			(layer "F.SilkS")
		)
		(fp_line
			(start -0.7874 0.4064)
			(end -0.7874 -0.4064)
			(stroke
				(width 0.1524)
				(type default)
			)
			(layer "F.SilkS")
		)
		(fp_line
			(start -0.7874 -0.4064)
			(end 0.7874 -0.4064)
			(stroke
				(width 0.1524)
				(type default)
			)
			(layer "F.SilkS")
		)
		(fp_line
			(start 0.67945 0.3048)
			(end 0.120396 0.3048)
			(stroke
				(width 0.1)
				(type default)
			)
			(layer "F.Fab")
		)
		(fp_line
			(start 0.67945 -0.3048)
			(end 0.67945 0.3048)
			(stroke
				(width 0.1)
				(type default)
			)
			(layer "F.Fab")
		)
		(fp_line
			(start 0.12065 -0.2794)
			(end 0.12065 -0.3048)
			(stroke
				(width 0.1)
				(type default)
			)
			(layer "F.Fab")
		)
		(fp_line
			(start 0.12065 -0.3048)
			(end 0.67945 -0.3048)
			(stroke
				(width 0.1)
				(type default)
			)
			(layer "F.Fab")
		)
		(fp_line
			(start 0.120396 0.3048)
			(end 0.120396 0.2794)
			(stroke
				(width 0.1)
				(type default)
			)
			(layer "F.Fab")
		)
		(fp_line
			(start 0.120396 0.2794)
			(end -0.12065 0.2794)
			(stroke
				(width 0.1)
				(type default)
			)
			(layer "F.Fab")
		)
		(fp_line
			(start -0.12065 0.3048)
			(end -0.67945 0.3048)
			(stroke
				(width 0.1)
				(type default)
			)
			(layer "F.Fab")
		)
		(fp_line
			(start -0.12065 0.2794)
			(end -0.12065 0.3048)
			(stroke
				(width 0.1)
				(type default)
			)
			(layer "F.Fab")
		)
		(fp_line
			(start -0.12065 -0.2794)
			(end 0.12065 -0.2794)
			(stroke
				(width 0.1)
				(type default)
			)
			(layer "F.Fab")
		)
		(fp_line
			(start -0.12065 -0.305054)
			(end -0.12065 -0.2794)
			(stroke
				(width 0.1)
				(type default)
			)
			(layer "F.Fab")
		)
		(fp_line
			(start -0.67945 0.3048)
			(end -0.67945 -0.305054)
			(stroke
				(width 0.1)
				(type default)
			)
			(layer "F.Fab")
		)
		(fp_line
			(start -0.67945 -0.305054)
			(end -0.12065 -0.305054)
			(stroke
				(width 0.1)
				(type default)
			)
			(layer "F.Fab")
		)
		(pad "1" smd circle
			(at -0.40005 0 180)
			(size 0 0)
			(layers "F.Cu" "F.Mask" "F.Paste")
			(net "P3V3_AUX")
		)
		(pad "2" smd circle
			(at 0.40005 0 180)
			(size 0 0)
			(layers "F.Cu" "F.Mask" "F.Paste")
			(net "GND")
		)
	)
)
